# T6G (Grand Teton) — schematic netlist excerpt (pin names and nets, part order shuffled) for the footprints in the layout excerpt that follows; sources: Cadence DE-HDL packaged netlist, KiCad conversion of 04192023_DAF0TMB3IC0_F0TG_MB_C_brd_V02_OCP.brd

C1775  Q_CAP  0.1UF 25V 10% X7R  pkg 0402  page 241 : A = P3V3_AUX ; B = GND
R714  Q_RES  1K 1% CHIP  pkg 0402LF  page 238 : A = MB_FRU_ADDR2 ; B = GND

(kicad_pcb
	(version 20260206)
	(generator "pcbnew")
	(generator_version "10.0")
	(general
		(thickness 1.6)
		(legacy_teardrops no)
	)
	(paper "A4")
	(title_block
		(title "04192023_DAF0TMB3IC0_F0TG_MB_C_brd_V02_OCP.brd")
		(comment 1 "Grand Teton / footprints 3252-3253 of 8354")
	)
	(layers
		(0 "F.Cu" signal "TOP")
		(4 "In1.Cu" signal "GND")
		(6 "In2.Cu" signal "IN1")
		(8 "In3.Cu" signal "GND1")
		(10 "In4.Cu" signal "IN2")
		(12 "In5.Cu" signal "GND2")
		(14 "In6.Cu" signal "IN3")
		(16 "In7.Cu" signal "GND3")
		(18 "In8.Cu" signal "VCC")
		(20 "In9.Cu" signal "VCC1")
		(22 "In10.Cu" signal "GND4")
		(24 "In11.Cu" signal "IN4")
		(26 "In12.Cu" signal "GND5")
		(28 "In13.Cu" signal "IN5")
		(30 "In14.Cu" signal "GND6")
		(32 "In15.Cu" signal "IN6")
		(34 "In16.Cu" signal "GND7")
		(2 "B.Cu" signal "BOTTOM")
		(9 "F.Adhes" user "F.Adhesive")
		(11 "B.Adhes" user "B.Adhesive")
		(13 "F.Paste" user "Package Geometry/Pastemask Top")
		(15 "B.Paste" user "Package Geometry/Pastemask Bottom")
		(5 "F.SilkS" user "Ref Des/Silkscreen Top")
		(7 "B.SilkS" user "Ref Des/Silkscreen Bottom")
		(1 "F.Mask" user "Board Geometry/Soldermask Top")
		(3 "B.Mask" user "Board Geometry/Soldermask Bottom")
		(17 "Dwgs.User" user "User.Drawings")
		(19 "Cmts.User" user "User.Comments")
		(21 "Eco1.User" user "User.Eco1")
		(23 "Eco2.User" user "User.Eco2")
		(25 "Edge.Cuts" user "Board Geometry/Outline")
		(27 "Margin" user)
		(31 "F.CrtYd" user "Package Geometry/Place Bound Top")
		(29 "B.CrtYd" user "Package Geometry/Place Bound Bottom")
		(35 "F.Fab" user "Ref Des/Assembly Top")
		(33 "B.Fab" user "Ref Des/Assembly Bottom")
	)
	(footprint ""
		(layer "F.Cu")
		(at 191.52362 -421.026082 90)
		(property "Reference" "C1775"
			(at 0 0 90)
			(layer "F.SilkS")
			(hide yes)
			(effects
				(font
					(size 1.27 1.27)
				)
			)
		)
		(property "Value" ""
			(at 0 0 90)
			(layer "F.Fab")
			(effects
				(font
					(size 1.27 1.27)
				)
			)
		)
		(duplicate_pad_numbers_are_jumpers no)
		(fp_line
			(start 0.7874 -0.4064)
			(end 0.7874 0.4064)
			(stroke
				(width 0.1524)
				(type default)
			)
			(layer "F.SilkS")
		)
		(fp_line
			(start -0.7874 -0.4064)
			(end 0.7874 -0.4064)
			(stroke
				(width 0.1524)
				(type default)
			)
			(layer "F.SilkS")
		)
		(fp_line
			(start 0.7874 0.4064)
			(end -0.7874 0.4064)
			(stroke
				(width 0.1524)
				(type default)
			)
			(layer "F.SilkS")
		)
		(fp_line
			(start -0.7874 0.4064)
			(end -0.7874 -0.4064)
			(stroke
				(width 0.1524)
				(type default)
			)
			(layer "F.SilkS")
		)
		(fp_line
			(start -0.12065 -0.305054)
			(end -0.12065 -0.2794)
			(stroke
				(width 0.1)
				(type default)
			)
			(layer "F.Fab")
		)
		(fp_line
			(start -0.67945 -0.305054)
			(end -0.12065 -0.305054)
			(stroke
				(width 0.1)
				(type default)
			)
			(layer "F.Fab")
		)
		(fp_line
			(start 0.67945 -0.3048)
			(end 0.67945 0.3048)
			(stroke
				(width 0.1)
				(type default)
			)
			(layer "F.Fab")
		)
		(fp_line
			(start 0.12065 -0.3048)
			(end 0.67945 -0.3048)
			(stroke
				(width 0.1)
				(type default)
			)
			(layer "F.Fab")
		)
		(fp_line
			(start 0.12065 -0.2794)
			(end 0.12065 -0.3048)
			(stroke
				(width 0.1)
				(type default)
			)
			(layer "F.Fab")
		)
		(fp_line
			(start -0.12065 -0.2794)
			(end 0.12065 -0.2794)
			(stroke
				(width 0.1)
				(type default)
			)
			(layer "F.Fab")
		)
		(fp_line
			(start 0.120396 0.2794)
			(end -0.12065 0.2794)
			(stroke
				(width 0.1)
				(type default)
			)
			(layer "F.Fab")
		)
		(fp_line
			(start -0.12065 0.2794)
			(end -0.12065 0.3048)
			(stroke
				(width 0.1)
				(type default)
			)
			(layer "F.Fab")
		)
		(fp_line
			(start 0.67945 0.3048)
			(end 0.120396 0.3048)
			(stroke
				(width 0.1)
				(type default)
			)
			(layer "F.Fab")
		)
		(fp_line
			(start 0.120396 0.3048)
			(end 0.120396 0.2794)
			(stroke
				(width 0.1)
				(type default)
			)
			(layer "F.Fab")
		)
		(fp_line
			(start -0.12065 0.3048)
			(end -0.67945 0.3048)
			(stroke
				(width 0.1)
				(type default)
			)
			(layer "F.Fab")
		)
		(fp_line
			(start -0.67945 0.3048)
			(end -0.67945 -0.305054)
			(stroke
				(width 0.1)
				(type default)
			)
			(layer "F.Fab")
		)
		(pad "1" smd circle
			(at -0.40005 0 90)
			(size 0 0)
			(layers "F.Cu" "F.Mask" "F.Paste")
			(net "P3V3_AUX")
		)
		(pad "2" smd circle
			(at 0.40005 0 90)
			(size 0 0)
			(layers "F.Cu" "F.Mask" "F.Paste")
			(net "GND")
		)
	)
	(footprint ""
		(layer "F.Cu")
		(at 302.241458 -116.891308 180)
		(property "Reference" "R714"
			(at 0 0 180)
			(layer "F.SilkS")
			(hide yes)
			(effects
				(font
					(size 1.27 1.27)
				)
			)
		)
		(property "Value" ""
			(at 0 0 180)
			(layer "F.Fab")
			(effects
				(font
					(size 1.27 1.27)
				)
			)
		)
		(duplicate_pad_numbers_are_jumpers no)
		(fp_line
			(start 0.7874 0.4064)
			(end -0.7874 0.4064)
			(stroke
				(width 0.1524)
				(type default)
			)
			(layer "F.SilkS")
		)
		(fp_line
			(start 0.7874 -0.4064)
			(end 0.7874 0.4064)
			(stroke
				(width 0.1524)
				(type default)
			)
			(layer "F.SilkS")
		)
		(fp_line
			(start -0.7874 0.4064)
			(end -0.7874 -0.4064)
			(stroke
				(width 0.1524)
				(type default)
			)
			(layer "F.SilkS")
		)
		(fp_line
			(start -0.7874 -0.4064)
			(end 0.7874 -0.4064)
			(stroke
				(width 0.1524)
				(type default)
			)
			(layer "F.SilkS")
		)
		(fp_line
			(start 0.67945 0.3048)
			(end 0.120396 0.3048)
			(stroke
				(width 0.1)
				(type default)
			)
			(layer "F.Fab")
		)
		(fp_line
			(start 0.67945 -0.3048)
			(end 0.67945 0.3048)
			(stroke
				(width 0.1)
				(type default)
			)
			(layer "F.Fab")
		)
		(fp_line
			(start 0.12065 -0.2794)
			(end 0.12065 -0.3048)
			(stroke
				(width 0.1)
				(type default)
			)
			(layer "F.Fab")
		)
		(fp_line
			(start 0.12065 -0.3048)
			(end 0.67945 -0.3048)
			(stroke
				(width 0.1)
				(type default)
			)
			(layer "F.Fab")
		)
		(fp_line
			(start 0.120396 0.3048)
			(end 0.120396 0.2794)
			(stroke
				(width 0.1)
				(type default)
			)
			(layer "F.Fab")
		)
		(fp_line
			(start 0.120396 0.2794)
			(end -0.12065 0.2794)
			(stroke
				(width 0.1)
				(type default)
			)
			(layer "F.Fab")
		)
		(fp_line
			(start -0.12065 0.3048)
			(end -0.67945 0.3048)
			(stroke
				(width 0.1)
				(type default)
			)
			(layer "F.Fab")
		)
		(fp_line
			(start -0.12065 0.2794)
			(end -0.12065 0.3048)
			(stroke
				(width 0.1)
				(type default)
			)
			(layer "F.Fab")
		)
		(fp_line
			(start -0.12065 -0.2794)
			(end 0.12065 -0.2794)
			(stroke
				(width 0.1)
				(type default)
			)
			(layer "F.Fab")
		)
		(fp_line
			(start -0.12065 -0.305054)
			(end -0.12065 -0.2794)
			(stroke
				(width 0.1)
				(type default)
			)
			(layer "F.Fab")
		)
		(fp_line
			(start -0.67945 0.3048)
			(end -0.67945 -0.305054)
			(stroke
				(width 0.1)
				(type default)
			)
			(layer "F.Fab")
		)
		(fp_line
			(start -0.67945 -0.305054)
			(end -0.12065 -0.305054)
			(stroke
				(width 0.1)
				(type default)
			)
			(layer "F.Fab")
		)
		(pad "1" smd circle
			(at -0.40005 0 180)
			(size 0 0)
			(layers "F.Cu" "F.Mask" "F.Paste")
			(net "MB_FRU_ADDR2")
		)
		(pad "2" smd circle
			(at 0.40005 0 180)
			(size 0 0)
			(layers "F.Cu" "F.Mask" "F.Paste")
			(net "GND")
		)
	)
)
